# BASEBOARD_FAB2 (Tioga Pass) — schematic netlist excerpt (pin names and nets, part order shuffled) for the footprints in the layout excerpt that follows; sources: Cadence DE-HDL packaged netlist, KiCad conversion of Wiwynn_Tioga_Pass_MB.brd

J9U1  SCONN288_H44441003  SCONN  pkg PIP  page 80
  \12v\(1)  = P12V_NVDIMM_GHJ
  VSS(93)  = GND
  DQ(4)  = M_H_DQ<4>
  VSS(92)  = GND
  DQ(0)  = M_H_DQ<0>
  VSS(91)  = GND
  DQS9P  = M_H_DQS_DP<9>
  DQS9N  = M_H_DQS_DN<9>
  VSS(90)  = GND
  DQ(6)  = M_H_DQ<6>
  VSS(89)  = GND
  DQ(2)  = M_H_DQ<2>
  VSS(88)  = GND
  DQ(12)  = M_H_DQ<12>
  VSS(87)  = GND
  DQ(8)  = M_H_DQ<8>
  VSS(86)  = GND
  DQS10P  = M_H_DQS_DP<10>
  DQS10N  = M_H_DQS_DN<10>
  VSS(85)  = GND
  DQ(14)  = M_H_DQ<14>
  VSS(84)  = GND
  DQ(10)  = M_H_DQ<10>
  VSS(83)  = GND
  DQ(20)  = M_H_DQ<20>
  VSS(82)  = GND
  DQ(16)  = M_H_DQ<16>
  VSS(81)  = GND
  DQS11P  = M_H_DQS_DP<11>
  DQS11N  = M_H_DQS_DN<11>
  VSS(80)  = GND
  DQ(22)  = M_H_DQ<22>
  VSS(79)  = GND
  DQ(18)  = M_H_DQ<18>
  VSS(78)  = GND
  DQ(28)  = M_H_DQ<28>
  VSS(77)  = GND
  DQ(24)  = M_H_DQ<24>
  VSS(76)  = GND
  DQS12P  = M_H_DQS_DP<12>
  DQS12N  = M_H_DQS_DN<12>
  VSS(75)  = GND
  DQ(30)  = M_H_DQ<30>
  VSS(74)  = GND
  DQ(26)  = M_H_DQ<26>
  VSS(73)  = GND
  CB(4)  = M_H_ECC<4>
  VSS(72)  = GND
  CB(0)  = M_H_ECC<0>
  VSS(71)  = GND
  DQS17P  = M_H_DQS_DP<17>
  DQS17N  = M_H_DQS_DN<17>
  VSS(70)  = GND
  CB(6)  = M_H_ECC<6>
  VSS(69)  = GND
  CB(2)  = M_H_ECC<2>
  VSS(68)  = GND
  RESET_N  = M_GHJ_RST_N
  VDD(25)  = PVDDQ_GHJ
  CKE(0)  = M_H_CKE<2>
  VDD(24)  = PVDDQ_GHJ
  ACT_N  = M_H_ACT_N
  BG(0)  = M_H_BG<0>
  VDD(23)  = PVDDQ_GHJ
  A12  = M_H_MA<12>
  A9  = M_H_MA<9>
  VDD(22)  = PVDDQ_GHJ
  A8  = M_H_MA<8>
  A6  = M_H_MA<6>
  VDD(21)  = PVDDQ_GHJ
  A3  = M_H_MA<3>
  A1  = M_H_MA<1>
  VDD(20)  = PVDDQ_GHJ
  CK0P  = M_H_CLK_DP<2>
  CK0N  = M_H_CLK_DN<2>
  VDD(19)  = PVDDQ_GHJ
  VTT(1)  = PVTT_GHJ
  EVENT_N  = FM_DIMM_EVENT_COD_N
  A0  = M_H_MA<0>
  VDD(18)  = PVDDQ_GHJ
  BA(0)  = M_H_BA<0>
  A16_RAS_N  = M_H_MA<16>
  VDD(17)  = PVDDQ_GHJ
  S0_N  = M_H_CS_N<4>
  VDD(16)  = PVDDQ_GHJ
  A15_CAS_N  = M_H_MA<15>
  ODT(0)  = M_H_ODT<2>
  VDD(15)  = PVDDQ_GHJ
  S1_N  = M_H_CS_N<5>
  VDD(14)  = PVDDQ_GHJ
  ODT(1)  = M_H_ODT<3>
  VDD(13)  = PVDDQ_GHJ
  S2_N_C(0)  = M_H_CS_N<6>
  VSS(67)  = GND
  DQ(36)  = M_H_DQ<36>
  VSS(66)  = GND
  DQ(32)  = M_H_DQ<32>
  VSS(65)  = GND
  DQS13P  = M_H_DQS_DP<13>
  DQS13N  = M_H_DQS_DN<13>
  VSS(64)  = GND
  DQ(38)  = M_H_DQ<38>
  VSS(63)  = GND
  DQ(34)  = M_H_DQ<34>
  VSS(62)  = GND
  DQ(44)  = M_H_DQ<44>
  VSS(61)  = GND
  DQ(40)  = M_H_DQ<40>
  VSS(60)  = GND
  DQS14P  = M_H_DQS_DP<14>
  DQS14N  = M_H_DQS_DN<14>
  VSS(59)  = GND
  DQ(46)  = M_H_DQ<46>
  VSS(58)  = GND
  DQ(42)  = M_H_DQ<42>
  VSS(57)  = GND
  DQ(52)  = M_H_DQ<52>
  VSS(56)  = GND
  DQ(48)  = M_H_DQ<48>
  VSS(55)  = GND
  DQS15P  = M_H_DQS_DP<15>
  DQS15N  = M_H_DQS_DN<15>
  VSS(54)  = GND
  DQ(54)  = M_H_DQ<54>
  VSS(53)  = GND
  DQ(50)  = M_H_DQ<50>
  VSS(52)  = GND
  DQ(60)  = M_H_DQ<60>
  VSS(51)  = GND
  DQ(56)  = M_H_DQ<56>
  VSS(50)  = GND
  DQS16P  = M_H_DQS_DP<16>
  DQS16N  = M_H_DQS_DN<16>
  VSS(49)  = GND
  DQ(62)  = M_H_DQ<62>
  VSS(48)  = GND
  DQ(58)  = M_H_DQ<58>
  VSS(47)  = GND
  SA(0)  = PVPP_GHJ
  SA(1)  = PVPP_GHJ
  SCL  = SMB_DDR_GHJ_VPP_SCL
  VPP(4)  = PVPP_GHJ
  VPP(3)  = PVPP_GHJ
  RFU(2)  = TP_CH_H_DIMM0_RFU_2
  \12v\(0)  = P12V_NVDIMM_GHJ
  VREFCA  = M_H_VREF
  VSS(46)  = GND
  DQ(5)  = M_H_DQ<5>
  VSS(45)  = GND
  DQ(1)  = M_H_DQ<1>
  VSS(44)  = GND
  DQS0N  = M_H_DQS_DN<0>
  DQS0P  = M_H_DQS_DP<0>
  VSS(43)  = GND
  DQ(7)  = M_H_DQ<7>
  VSS(42)  = GND
  DQ(3)  = M_H_DQ<3>
  VSS(41)  = GND
  DQ(13)  = M_H_DQ<13>
  VSS(40)  = GND
  DQ(9)  = M_H_DQ<9>
  VSS(39)  = GND
  DQS1N  = M_H_DQS_DN<1>
  DQS1P  = M_H_DQS_DP<1>
  VSS(38)  = GND
  DQ(15)  = M_H_DQ<15>
  VSS(37)  = GND
  DQ(11)  = M_H_DQ<11>
  VSS(36)  = GND
  DQ(21)  = M_H_DQ<21>
  VSS(35)  = GND
  DQ(17)  = M_H_DQ<17>
  VSS(34)  = GND
  DQS2N  = M_H_DQS_DN<2>
  DQS2P  = M_H_DQS_DP<2>
  VSS(33)  = GND
  DQ(23)  = M_H_DQ<23>
  VSS(32)  = GND
  DQ(19)  = M_H_DQ<19>
  VSS(31)  = GND
  DQ(29)  = M_H_DQ<29>
  VSS(30)  = GND
  DQ(25)  = M_H_DQ<25>
  VSS(29)  = GND
  DQS3N  = M_H_DQS_DN<3>
  DQS3P  = M_H_DQS_DP<3>
  VSS(28)  = GND
  DQ(31)  = M_H_DQ<31>
  VSS(27)  = GND
  DQ(27)  = M_H_DQ<27>
  VSS(26)  = GND
  CB(5)  = M_H_ECC<5>
  VSS(25)  = GND
  CB(1)  = M_H_ECC<1>
  VSS(24)  = GND
  DQS8N  = M_H_DQS_DN<8>
  DQS8P  = M_H_DQS_DP<8>
  VSS(23)  = GND
  CB(7)  = M_H_ECC<7>
  VSS(22)  = GND
  CB(3)  = M_H_ECC<3>
  VSS(21)  = GND
  CKE(1)  = M_H_CKE<3>
  VDD(12)  = PVDDQ_GHJ
  RFU(0)  = TP_CH_H_DIMM0_RFU_0
  VDD(11)  = PVDDQ_GHJ
  BG(1)  = M_H_BG<1>
  ALERT_N  = M_H_ALERT_N
  VDD(10)  = PVDDQ_GHJ
  A11  = M_H_MA<11>
  A7  = M_H_MA<7>
  VDD(9)  = PVDDQ_GHJ
  A5  = M_H_MA<5>
  A4  = M_H_MA<4>
  VDD(8)  = PVDDQ_GHJ
  A2  = M_H_MA<2>
  VDD(7)  = PVDDQ_GHJ
  CK1P  = M_H_CLK_DP<3>
  CK1N  = M_H_CLK_DN<3>
  VDD(6)  = PVDDQ_GHJ
  VTT(0)  = PVTT_GHJ
  PAR  = M_H_PAR
  VDD(5)  = PVDDQ_GHJ
  BA(1)  = M_H_BA<1>
  A10  = M_H_MA<10>
  VDD(4)  = PVDDQ_GHJ
  RFU(1)  = TP_CH_H_DIMM0_RFU_1
  A14_WE_N  = M_H_MA<14>
  VDD(3)  = PVDDQ_GHJ
  SAVE_N_NC  = FM_ADR_COMPLETE_GHJ_N
  VDD(2)  = PVDDQ_GHJ
  A13  = M_H_MA<13>
  VDD(1)  = PVDDQ_GHJ
  A17  = M_H_MA<17>
  C(2)  = M_H_C<2>
  VDD(0)  = PVDDQ_GHJ
  S3_N_C(1)  = M_H_CS_N<7>
  SA(2)  = GND
  VSS(20)  = GND
  DQ(37)  = M_H_DQ<37>
  VSS(19)  = GND
  DQ(33)  = M_H_DQ<33>
  VSS(18)  = GND
  DQS4N  = M_H_DQS_DN<4>
  DQS4P  = M_H_DQS_DP<4>
  VSS(17)  = GND
  DQ(39)  = M_H_DQ<39>
  VSS(16)  = GND
  DQ(35)  = M_H_DQ<35>
  VSS(15)  = GND
  DQ(45)  = M_H_DQ<45>
  VSS(14)  = GND
  DQ(41)  = M_H_DQ<41>
  VSS(13)  = GND
  DQS5N  = M_H_DQS_DN<5>
  DQS5P  = M_H_DQS_DP<5>
  VSS(12)  = GND
  DQ(47)  = M_H_DQ<47>
  VSS(11)  = GND
  DQ(43)  = M_H_DQ<43>
  VSS(10)  = GND
  DQ(53)  = M_H_DQ<53>
  VSS(9)  = GND
  DQ(49)  = M_H_DQ<49>
  VSS(8)  = GND
  DQS6N  = M_H_DQS_DN<6>
  DQS6P  = M_H_DQS_DP<6>
  VSS(7)  = GND
  DQ(55)  = M_H_DQ<55>
  VSS(6)  = GND
  DQ(51)  = M_H_DQ<51>
  VSS(5)  = GND
  DQ(61)  = M_H_DQ<61>
  VSS(4)  = GND
  DQ(57)  = M_H_DQ<57>
  VSS(3)  = GND
  DQS7N  = M_H_DQS_DN<7>
  DQS7P  = M_H_DQS_DP<7>
  VSS(2)  = GND
  DQ(63)  = M_H_DQ<63>
  VSS(1)  = GND
  DQ(59)  = M_H_DQ<59>
  VSS(0)  = GND
  VDDSPD  = PVPP_GHJ
  SDA  = SMB_DDR_GHJ_VPP_SDA
  VPP(1)  = PVPP_GHJ
  VPP(0)  = PVPP_GHJ
  VPP(2)  = PVPP_GHJ

(kicad_pcb
	(version 20260206)
	(generator "pcbnew")
	(generator_version "10.0")
	(general
		(thickness 1.6)
		(legacy_teardrops no)
	)
	(paper "A4")
	(title_block
		(title "Wiwynn_Tioga_Pass_MB.brd")
		(comment 1 "Tioga Pass / footprint 3114 of 4770 (J9U1), pads 101-151 of 291")
	)
	(layers
		(0 "F.Cu" signal "TOP")
		(4 "In1.Cu" signal "L2GND")
		(6 "In2.Cu" signal "L3")
		(8 "In3.Cu" signal "L4GND")
		(10 "In4.Cu" signal "L5")
		(12 "In5.Cu" signal "L6GND")
		(14 "In6.Cu" signal "L7VCC")
		(16 "In7.Cu" signal "L8VCC")
		(18 "In8.Cu" signal "L9GND")
		(20 "In9.Cu" signal "L10")
		(22 "In10.Cu" signal "L11GND")
		(24 "In11.Cu" signal "L12")
		(26 "In12.Cu" signal "L13GND")
		(2 "B.Cu" signal "BOTTOM")
		(9 "F.Adhes" user "F.Adhesive")
		(11 "B.Adhes" user "B.Adhesive")
		(13 "F.Paste" user "Package Geometry/Pastemask Top")
		(15 "B.Paste" user "Package Geometry/Pastemask Bottom")
		(5 "F.SilkS" user "Ref Des/Silkscreen Top")
		(7 "B.SilkS" user "Ref Des/Silkscreen Bottom")
		(1 "F.Mask" user "Board Geometry/Soldermask Top")
		(3 "B.Mask" user "Board Geometry/Soldermask Bottom")
		(17 "Dwgs.User" user "User.Drawings")
		(19 "Cmts.User" user "User.Comments")
		(21 "Eco1.User" user "User.Eco1")
		(23 "Eco2.User" user "User.Eco2")
		(25 "Edge.Cuts" user "Board Geometry/Outline")
		(27 "Margin" user)
		(31 "F.CrtYd" user "Package Geometry/Place Bound Top")
		(29 "B.CrtYd" user "Package Geometry/Place Bound Bottom")
		(35 "F.Fab" user "Ref Des/Assembly Top")
		(33 "B.Fab" user "Ref Des/Assembly Bottom")
	)
	(footprint ""
		(layer "B.Cu")
		(at 29.699458 -15.222982 90)
		(property "Reference" "J9U1"
			(at 2.276348 37.991542 0)
			(unlocked yes)
			(layer "B.SilkS")
			(effects
				(font
					(size 0.7874 0.5842)
					(thickness 0.1524)
				)
				(justify left mirror)
			)
		)
		(property "Value" ""
			(at 0 0 90)
			(layer "B.Fab")
			(effects
				(font
					(size 1.27 1.27)
				)
				(justify mirror)
			)
		)
		(duplicate_pad_numbers_are_jumpers no)
		(pad "98" smd rect
			(at 0 87.54999 270)
			(size 1.8034 0.508)
			(layers "B.Cu" "B.Mask" "B.Paste")
			(net "GND")
		)
		(pad "99" smd rect
			(at 0 88.399874 270)
			(size 1.8034 0.508)
			(layers "B.Cu" "B.Mask" "B.Paste")
			(net "M_H_DQS_DP<13>")
		)
		(pad "100" smd rect
			(at 0 89.250012 270)
			(size 1.8034 0.508)
			(layers "B.Cu" "B.Mask" "B.Paste")
			(net "M_H_DQS_DN<13>")
		)
		(pad "101" smd rect
			(at 0 90.099896 270)
			(size 1.8034 0.508)
			(layers "B.Cu" "B.Mask" "B.Paste")
			(net "GND")
		)
		(pad "102" smd rect
			(at 0 90.950034 270)
			(size 1.8034 0.508)
			(layers "B.Cu" "B.Mask" "B.Paste")
			(net "M_H_DQ<38>")
		)
		(pad "103" smd rect
			(at 0 91.799918 270)
			(size 1.8034 0.508)
			(layers "B.Cu" "B.Mask" "B.Paste")
			(net "GND")
		)
		(pad "104" smd rect
			(at 0 92.650056 270)
			(size 1.8034 0.508)
			(layers "B.Cu" "B.Mask" "B.Paste")
			(net "M_H_DQ<34>")
		)
		(pad "105" smd rect
			(at 0 93.49994 270)
			(size 1.8034 0.508)
			(layers "B.Cu" "B.Mask" "B.Paste")
			(net "GND")
		)
		(pad "106" smd rect
			(at 0 94.350078 270)
			(size 1.8034 0.508)
			(layers "B.Cu" "B.Mask" "B.Paste")
			(net "M_H_DQ<44>")
		)
		(pad "107" smd rect
			(at 0 95.199962 270)
			(size 1.8034 0.508)
			(layers "B.Cu" "B.Mask" "B.Paste")
			(net "GND")
		)
		(pad "108" smd rect
			(at 0 96.0501 270)
			(size 1.8034 0.508)
			(layers "B.Cu" "B.Mask" "B.Paste")
			(net "M_H_DQ<40>")
		)
		(pad "109" smd rect
			(at 0 96.899984 270)
			(size 1.8034 0.508)
			(layers "B.Cu" "B.Mask" "B.Paste")
			(net "GND")
		)
		(pad "110" smd rect
			(at 0 97.750122 270)
			(size 1.8034 0.508)
			(layers "B.Cu" "B.Mask" "B.Paste")
			(net "M_H_DQS_DP<14>")
		)
		(pad "111" smd rect
			(at 0 98.600006 270)
			(size 1.8034 0.508)
			(layers "B.Cu" "B.Mask" "B.Paste")
			(net "M_H_DQS_DN<14>")
		)
		(pad "112" smd rect
			(at 0 99.44989 270)
			(size 1.8034 0.508)
			(layers "B.Cu" "B.Mask" "B.Paste")
			(net "GND")
		)
		(pad "113" smd rect
			(at 0 100.300028 270)
			(size 1.8034 0.508)
			(layers "B.Cu" "B.Mask" "B.Paste")
			(net "M_H_DQ<46>")
		)
		(pad "114" smd rect
			(at 0 101.149912 270)
			(size 1.8034 0.508)
			(layers "B.Cu" "B.Mask" "B.Paste")
			(net "GND")
		)
		(pad "115" smd rect
			(at 0 102.00005 270)
			(size 1.8034 0.508)
			(layers "B.Cu" "B.Mask" "B.Paste")
			(net "M_H_DQ<42>")
		)
		(pad "116" smd rect
			(at 0 102.849934 270)
			(size 1.8034 0.508)
			(layers "B.Cu" "B.Mask" "B.Paste")
			(net "GND")
		)
		(pad "117" smd rect
			(at 0 103.700072 270)
			(size 1.8034 0.508)
			(layers "B.Cu" "B.Mask" "B.Paste")
			(net "M_H_DQ<52>")
		)
		(pad "118" smd rect
			(at 0 104.549956 270)
			(size 1.8034 0.508)
			(layers "B.Cu" "B.Mask" "B.Paste")
			(net "GND")
		)
		(pad "119" smd rect
			(at 0 105.400094 270)
			(size 1.8034 0.508)
			(layers "B.Cu" "B.Mask" "B.Paste")
			(net "M_H_DQ<48>")
		)
		(pad "120" smd rect
			(at 0 106.249978 270)
			(size 1.8034 0.508)
			(layers "B.Cu" "B.Mask" "B.Paste")
			(net "GND")
		)
		(pad "121" smd rect
			(at 0 107.100116 270)
			(size 1.8034 0.508)
			(layers "B.Cu" "B.Mask" "B.Paste")
			(net "M_H_DQS_DP<15>")
		)
		(pad "122" smd rect
			(at 0 107.95 270)
			(size 1.8034 0.508)
			(layers "B.Cu" "B.Mask" "B.Paste")
			(net "M_H_DQS_DN<15>")
		)
		(pad "123" smd rect
			(at 0 108.799884 270)
			(size 1.8034 0.508)
			(layers "B.Cu" "B.Mask" "B.Paste")
			(net "GND")
		)
		(pad "124" smd rect
			(at 0 109.650022 270)
			(size 1.8034 0.508)
			(layers "B.Cu" "B.Mask" "B.Paste")
			(net "M_H_DQ<54>")
		)
		(pad "125" smd rect
			(at 0 110.499906 270)
			(size 1.8034 0.508)
			(layers "B.Cu" "B.Mask" "B.Paste")
			(net "GND")
		)
		(pad "126" smd rect
			(at 0 111.350044 270)
			(size 1.8034 0.508)
			(layers "B.Cu" "B.Mask" "B.Paste")
			(net "M_H_DQ<50>")
		)
		(pad "127" smd rect
			(at 0 112.199928 270)
			(size 1.8034 0.508)
			(layers "B.Cu" "B.Mask" "B.Paste")
			(net "GND")
		)
		(pad "128" smd rect
			(at 0 113.050066 270)
			(size 1.8034 0.508)
			(layers "B.Cu" "B.Mask" "B.Paste")
			(net "M_H_DQ<60>")
		)
		(pad "129" smd rect
			(at 0 113.89995 270)
			(size 1.8034 0.508)
			(layers "B.Cu" "B.Mask" "B.Paste")
			(net "GND")
		)
		(pad "130" smd rect
			(at 0 114.750088 270)
			(size 1.8034 0.508)
			(layers "B.Cu" "B.Mask" "B.Paste")
			(net "M_H_DQ<56>")
		)
		(pad "131" smd rect
			(at 0 115.599972 270)
			(size 1.8034 0.508)
			(layers "B.Cu" "B.Mask" "B.Paste")
			(net "GND")
		)
		(pad "132" smd rect
			(at 0 116.45011 270)
			(size 1.8034 0.508)
			(layers "B.Cu" "B.Mask" "B.Paste")
			(net "M_H_DQS_DP<16>")
		)
		(pad "133" smd rect
			(at 0 117.299994 270)
			(size 1.8034 0.508)
			(layers "B.Cu" "B.Mask" "B.Paste")
			(net "M_H_DQS_DN<16>")
		)
		(pad "134" smd rect
			(at 0 118.149878 270)
			(size 1.8034 0.508)
			(layers "B.Cu" "B.Mask" "B.Paste")
			(net "GND")
		)
		(pad "135" smd rect
			(at 0 119.000016 270)
			(size 1.8034 0.508)
			(layers "B.Cu" "B.Mask" "B.Paste")
			(net "M_H_DQ<62>")
		)
		(pad "136" smd rect
			(at 0 119.8499 270)
			(size 1.8034 0.508)
			(layers "B.Cu" "B.Mask" "B.Paste")
			(net "GND")
		)
		(pad "137" smd rect
			(at 0 120.700038 270)
			(size 1.8034 0.508)
			(layers "B.Cu" "B.Mask" "B.Paste")
			(net "M_H_DQ<58>")
		)
		(pad "138" smd rect
			(at 0 121.549922 270)
			(size 1.8034 0.508)
			(layers "B.Cu" "B.Mask" "B.Paste")
			(net "GND")
		)
		(pad "139" smd rect
			(at 0 122.40006 270)
			(size 1.8034 0.508)
			(layers "B.Cu" "B.Mask" "B.Paste")
			(net "PVPP_GHJ")
		)
		(pad "140" smd rect
			(at 0 123.249944 270)
			(size 1.8034 0.508)
			(layers "B.Cu" "B.Mask" "B.Paste")
			(net "PVPP_GHJ")
		)
		(pad "141" smd rect
			(at 0 124.100082 270)
			(size 1.8034 0.508)
			(layers "B.Cu" "B.Mask" "B.Paste")
			(net "SMB_DDR_GHJ_VPP_SCL")
		)
		(pad "142" smd rect
			(at 0 124.949966 270)
			(size 1.8034 0.508)
			(layers "B.Cu" "B.Mask" "B.Paste")
			(net "PVPP_GHJ")
		)
		(pad "143" smd rect
			(at 0 125.800104 270)
			(size 1.8034 0.508)
			(layers "B.Cu" "B.Mask" "B.Paste")
			(net "PVPP_GHJ")
		)
		(pad "144" smd rect
			(at 0 126.649988 270)
			(size 1.8034 0.508)
			(layers "B.Cu" "B.Mask" "B.Paste")
			(net "TP_CH_H_DIMM0_RFU_2")
		)
		(pad "145" smd rect
			(at -4.59994 0 270)
			(size 1.8034 0.508)
			(layers "B.Cu" "B.Mask" "B.Paste")
			(net "P12V_NVDIMM_GHJ")
		)
		(pad "146" smd rect
			(at -4.59994 0.849884 270)
			(size 1.8034 0.508)
			(layers "B.Cu" "B.Mask" "B.Paste")
			(net "M_H_VREF")
		)
		(pad "147" smd rect
			(at -4.59994 1.700022 270)
			(size 1.8034 0.508)
			(layers "B.Cu" "B.Mask" "B.Paste")
			(net "GND")
		)
		(pad "148" smd rect
			(at -4.59994 2.549906 270)
			(size 1.8034 0.508)
			(layers "B.Cu" "B.Mask" "B.Paste")
			(net "M_H_DQ<5>")
		)
	)
)
